G04 ================== begin FILE IDENTIFICATION RECORD ==================*
G04 Layout Name:  15669-1.brd*
G04 Film Name:    BMASK*
G04 File Format:  Gerber RS274X*
G04 File Origin:  Cadence Allegro 16.5-S056*
G04 Origin Date:  Wed Nov 16 04:07:55 2016*
G04 *
G04 Layer:  VIA CLASS/SOLDERMASK_BOTTOM*
G04 Layer:  PIN/SOLDERMASK_BOTTOM*
G04 Layer:  PACKAGE GEOMETRY/SOLDERMASK_BOTTOM*
G04 Layer:  DRAWING FORMAT/LAYER_PCB_STORY*
G04 Layer:  DRAWING FORMAT/LAYER_SOLDER_B*
G04 Layer:  BOARD GEOMETRY/SOLDERMASK_BOTTOM*
G04 *
G04 Offset:    (0.00 0.00)*
G04 Mirror:    No*
G04 Mode:      Positive*
G04 Rotation:  0*
G04 FullContactRelief:  No*
G04 UndefLineWidth:     6.00*
G04 ================== end FILE IDENTIFICATION RECORD ====================*
%FSLAX35Y35*MOIN*%
%IR0*IPPOS*OFA0.00000B0.00000*MIA0B0*SFA1.00000B1.00000*%
%ADD19O,.103X.06*%
%ADD22R,.23X.032*%
%ADD18C,.02*%
%ADD13C,.034*%
%ADD11C,.08*%
%ADD20C,.073*%
%ADD16C,.028*%
%ADD10C,.086*%
%ADD14C,.087*%
%ADD17C,.315*%
%ADD15R,.098X.02*%
%ADD21C,.146*%
%ADD23C,.006*%
G75*
%LPD*%
G75*
G36*
G01X19685Y279134D02*
Y281470D01*
G02X47245I13780J38D01*
G01Y279134D01*
X41340D01*
Y281479D01*
G03X25590I-7875J31D01*
G01Y279134D01*
X19685D01*
G37*
G36*
G01D02*
Y281470D01*
G02X47245I13780J38D01*
G01Y279134D01*
X41340D01*
Y281479D01*
G03X25590I-7875J31D01*
G01Y279134D01*
X19685D01*
G37*
G36*
G01X7874Y1920473D02*
Y1922809D01*
G02X35434I13780J38D01*
G01Y1920473D01*
X29529D01*
Y1922818D01*
G03X13779I-7875J31D01*
G01Y1920473D01*
X7874D01*
G37*
G36*
G01D02*
Y1922809D01*
G02X35434I13780J38D01*
G01Y1920473D01*
X29529D01*
Y1922818D01*
G03X13779I-7875J31D01*
G01Y1920473D01*
X7874D01*
G37*
G36*
G01X120078Y15355D02*
Y17691D01*
G02X147638I13780J38D01*
G01Y15355D01*
X141733D01*
Y17700D01*
G03X125983I-7875J31D01*
G01Y15355D01*
X120078D01*
G37*
G36*
G01D02*
Y17691D01*
G02X147638I13780J38D01*
G01Y15355D01*
X141733D01*
Y17700D01*
G03X125983I-7875J31D01*
G01Y15355D01*
X120078D01*
G37*
G36*
G01X261811Y277166D02*
Y279502D01*
G02X289371I13780J38D01*
G01Y277166D01*
X283466D01*
Y279511D01*
G03X267716I-7875J31D01*
G01Y277166D01*
X261811D01*
G37*
G36*
G01D02*
Y279502D01*
G02X289371I13780J38D01*
G01Y277166D01*
X283466D01*
Y279511D01*
G03X267716I-7875J31D01*
G01Y277166D01*
X261811D01*
G37*
G36*
G01Y682668D02*
Y685004D01*
G02X289371I13780J38D01*
G01Y682668D01*
X283466D01*
Y685013D01*
G03X267716I-7875J31D01*
G01Y682668D01*
X261811D01*
G37*
G36*
G01D02*
Y685004D01*
G02X289371I13780J38D01*
G01Y682668D01*
X283466D01*
Y685013D01*
G03X267716I-7875J31D01*
G01Y682668D01*
X261811D01*
G37*
G36*
G01Y1086211D02*
Y1088547D01*
G02X289371I13780J38D01*
G01Y1086211D01*
X283466D01*
Y1088556D01*
G03X267716I-7875J31D01*
G01Y1086211D01*
X261811D01*
G37*
G36*
G01D02*
Y1088547D01*
G02X289371I13780J38D01*
G01Y1086211D01*
X283466D01*
Y1088556D01*
G03X267716I-7875J31D01*
G01Y1086211D01*
X261811D01*
G37*
G36*
G01Y1901172D02*
Y1903508D01*
G02X289371I13780J38D01*
G01Y1901172D01*
X283466D01*
Y1903517D01*
G03X267716I-7875J31D01*
G01Y1901172D01*
X261811D01*
G37*
G36*
G01D02*
Y1903508D01*
G02X289371I13780J38D01*
G01Y1901172D01*
X283466D01*
Y1903517D01*
G03X267716I-7875J31D01*
G01Y1901172D01*
X261811D01*
G37*
G36*
G01X984251Y161014D02*
Y163350D01*
G02X1011811I13780J38D01*
G01Y161014D01*
X1005906D01*
Y163359D01*
G03X990156I-7875J31D01*
G01Y161014D01*
X984251D01*
G37*
G36*
G01D02*
Y163350D01*
G02X1011811I13780J38D01*
G01Y161014D01*
X1005906D01*
Y163359D01*
G03X990156I-7875J31D01*
G01Y161014D01*
X984251D01*
G37*
G36*
G01Y684636D02*
Y686972D01*
G02X1011811I13780J38D01*
G01Y684636D01*
X1005906D01*
Y686981D01*
G03X990156I-7875J31D01*
G01Y684636D01*
X984251D01*
G37*
G36*
G01D02*
Y686972D01*
G02X1011811I13780J38D01*
G01Y684636D01*
X1005906D01*
Y686981D01*
G03X990156I-7875J31D01*
G01Y684636D01*
X984251D01*
G37*
G36*
G01Y1080305D02*
Y1082641D01*
G02X1011811I13780J38D01*
G01Y1080305D01*
X1005906D01*
Y1082650D01*
G03X990156I-7875J31D01*
G01Y1080305D01*
X984251D01*
G37*
G36*
G01D02*
Y1082641D01*
G02X1011811I13780J38D01*
G01Y1080305D01*
X1005906D01*
Y1082650D01*
G03X990156I-7875J31D01*
G01Y1080305D01*
X984251D01*
G37*
G36*
G01X1021245Y1493247D02*
Y1510922D01*
X995645D01*
Y1493247D01*
X1021245D01*
G37*
G36*
G01Y1473722D02*
Y1491397D01*
X995645D01*
Y1473722D01*
X1021245D01*
G37*
G36*
G01Y1453247D02*
Y1470922D01*
X995645D01*
Y1453247D01*
X1021245D01*
G37*
G36*
G01Y1433722D02*
Y1451397D01*
X995645D01*
Y1433722D01*
X1021245D01*
G37*
G36*
G01Y1573247D02*
Y1590922D01*
X995645D01*
Y1573247D01*
X1021245D01*
G37*
G36*
G01Y1553722D02*
Y1571397D01*
X995645D01*
Y1553722D01*
X1021245D01*
G37*
G36*
G01Y1533247D02*
Y1550922D01*
X995645D01*
Y1533247D01*
X1021245D01*
G37*
G36*
G01Y1513722D02*
Y1531397D01*
X995645D01*
Y1513722D01*
X1021245D01*
G37*
G36*
G01X1021244Y1593722D02*
Y1610922D01*
X995645D01*
Y1593722D01*
X1021244D01*
G37*
G36*
G01X984251Y1901172D02*
Y1903508D01*
G02X1011811I13780J38D01*
G01Y1901172D01*
X1005906D01*
Y1903517D01*
G03X990156I-7875J31D01*
G01Y1901172D01*
X984251D01*
G37*
G36*
G01D02*
Y1903508D01*
G02X1011811I13780J38D01*
G01Y1901172D01*
X1005906D01*
Y1903517D01*
G03X990156I-7875J31D01*
G01Y1901172D01*
X984251D01*
G37*
G54D10*
X-63741Y15000D03*
X-42339Y1008909D03*
X-63741Y1977126D03*
X25499Y1950499D03*
X1010999Y43999D03*
X1010499Y1950499D03*
X1101142Y15000D03*
Y1977126D03*
G54D20*
X82087Y28858D03*
Y178464D03*
Y434370D03*
Y583976D03*
Y839882D03*
Y989488D03*
Y1245394D03*
Y1395000D03*
Y1650906D03*
Y1800512D03*
X162008Y191614D03*
Y341220D03*
Y597126D03*
Y746732D03*
Y1002638D03*
Y1152244D03*
Y1408150D03*
Y1557756D03*
Y1813662D03*
Y1963268D03*
X890354Y191614D03*
Y341220D03*
Y597126D03*
Y746732D03*
Y1002638D03*
Y1152244D03*
Y1408150D03*
Y1557756D03*
Y1813662D03*
Y1963268D03*
G54D11*
X-49168Y52138D03*
X26000Y1965500D03*
X1009500Y27500D03*
X1010500Y1966000D03*
X1085741Y22661D03*
Y1967598D03*
G36*
G01X39370Y278851D02*
Y281496D01*
G03X27559I-5905J0D01*
G01Y278851D01*
G02X25809Y273902I-7873J0D01*
G03X41120I7656J-6187D01*
G02X39370Y278851I6123J4949D01*
G37*
G36*
G01X27559Y1920190D02*
Y1922835D01*
G03X15748I-5906J0D01*
G01Y1920190D01*
G02X13998Y1915241I-7873J0D01*
G03X29309I7656J-6187D01*
G02X27559Y1920190I6123J4949D01*
G37*
G36*
G01X139763Y15072D02*
Y17717D01*
G03X127952I-5906J0D01*
G01Y15072D01*
G02X126202Y10123I-7873J0D01*
G03X141513I7655J-6187D01*
G02X139763Y15072I6123J4949D01*
G37*
G36*
G01X281496Y276883D02*
Y279528D01*
G03X269685I-5905J0D01*
G01Y276883D01*
G02X267935Y271934I-7873J0D01*
G03X283246I7656J-6187D01*
G02X281496Y276883I6123J4949D01*
G37*
G36*
G01Y682385D02*
Y685030D01*
G03X269685I-5905J0D01*
G01Y682385D01*
G02X267935Y677436I-7873J0D01*
G03X283246I7656J-6187D01*
G02X281496Y682385I6123J4949D01*
G37*
G36*
G01Y1085928D02*
Y1088573D01*
G03X269685I-5905J0D01*
G01Y1085928D01*
G02X267935Y1080979I-7873J0D01*
G03X283246I7656J-6187D01*
G02X281496Y1085928I6123J4949D01*
G37*
G36*
G01Y1900889D02*
Y1903534D01*
G03X269685I-5905J0D01*
G01Y1900889D01*
G02X267935Y1895940I-7873J0D01*
G03X283246I7656J-6187D01*
G02X281496Y1900889I6123J4949D01*
G37*
G36*
G01X1003936Y160731D02*
Y163376D01*
G03X992125I-5905J0D01*
G01Y160731D01*
G02X990375Y155782I-7873J0D01*
G03X1005686I7656J-6187D01*
G02X1003936Y160731I6123J4949D01*
G37*
G36*
G01Y684353D02*
Y686998D01*
G03X992125I-5905J0D01*
G01Y684353D01*
G02X990375Y679404I-7873J0D01*
G03X1005686I7656J-6187D01*
G02X1003936Y684353I6123J4949D01*
G37*
G36*
G01Y1080022D02*
Y1082667D01*
G03X992125I-5905J0D01*
G01Y1080022D01*
G02X990375Y1075073I-7873J0D01*
G03X1005686I7656J-6187D01*
G02X1003936Y1080022I6123J4949D01*
G37*
G36*
G01Y1900889D02*
Y1903534D01*
G03X992125I-5905J0D01*
G01Y1900889D01*
G02X990375Y1895940I-7873J0D01*
G03X1005686I7656J-6187D01*
G02X1003936Y1900889I6123J4949D01*
G37*
G54D21*
X1023228Y1416024D03*
Y1694212D03*
G54D13*
X23426Y281496D03*
X24764Y286496D03*
X28426Y290197D03*
X38465D03*
X42166Y286496D03*
X11615Y1922835D03*
X12953Y1927835D03*
X16615Y1931536D03*
X26654D03*
X30355Y1927835D03*
X31693Y1922835D03*
X43504Y281496D03*
X123819Y17717D03*
X125157Y22717D03*
X128819Y26418D03*
X138858D03*
X142559Y22717D03*
X143897Y17717D03*
X265552Y279528D03*
X266890Y284528D03*
X270552Y288229D03*
X280591D03*
X284292Y284528D03*
X285630Y279528D03*
X265552Y685030D03*
X266890Y690030D03*
X270552Y693731D03*
X280591D03*
X284292Y690030D03*
X285630Y685030D03*
X265552Y1088573D03*
X266890Y1093573D03*
X270552Y1097274D03*
X280591D03*
X284292Y1093573D03*
X285630Y1088573D03*
X265552Y1903534D03*
X266890Y1908534D03*
X270552Y1912235D03*
X280591D03*
X284292Y1908534D03*
X285630Y1903534D03*
X987992Y163376D03*
Y686998D03*
Y1082667D03*
Y1903534D03*
X989330Y168376D03*
X992992Y172077D03*
X1003031D03*
X1006732Y168376D03*
X1008070Y163376D03*
X989330Y691998D03*
X992992Y695699D03*
X1003031D03*
X1006732Y691998D03*
X1008070Y686998D03*
X989330Y1087667D03*
X992992Y1091368D03*
X1003031D03*
X1006732Y1087667D03*
X1008070Y1082667D03*
X989330Y1908534D03*
X992992Y1912235D03*
X1003031D03*
X1006732Y1908534D03*
X1008070Y1903534D03*
G54D22*
X1009744Y1646102D03*
Y1641102D03*
Y1636102D03*
Y1631102D03*
Y1626102D03*
Y1621102D03*
Y1676102D03*
Y1671102D03*
Y1666102D03*
Y1661102D03*
Y1656102D03*
Y1651102D03*
G54D23*
G01X-90900Y-277455D02*
Y-294955D01*
X-82166D01*
G01X-69033Y-283289D02*
Y-294955D01*
G01Y-278622D02*
X-69470Y-278330D01*
Y-277747D01*
X-69033Y-277455D01*
X-68596Y-277747D01*
Y-278330D01*
X-69033Y-278622D01*
G01X-54590Y-299330D02*
X-53061Y-300497D01*
X-51315Y-300788D01*
X-49787Y-300497D01*
X-48476Y-299039D01*
X-47603Y-296997D01*
Y-283289D01*
G01Y-285622D02*
X-48476Y-284455D01*
X-49787Y-283580D01*
X-51315Y-283289D01*
X-53061Y-283872D01*
X-54153Y-285038D01*
X-55027Y-287080D01*
X-55463Y-289122D01*
X-55245Y-290872D01*
X-54371Y-292914D01*
X-53061Y-294372D01*
X-51315Y-294955D01*
X-50005Y-294663D01*
X-48476Y-293497D01*
X-47603Y-292331D01*
G01X-37745Y-294955D02*
Y-277455D01*
G01Y-285913D02*
X-36653Y-284455D01*
X-35561Y-283580D01*
X-33815Y-283289D01*
X-32505Y-283580D01*
X-30976Y-284747D01*
X-30321Y-286497D01*
Y-294955D01*
G01X-16533Y-277455D02*
Y-294955D01*
G01X-19590Y-283289D02*
X-13476D01*
G01X-2745Y-294955D02*
Y-283289D01*
G01Y-286205D02*
X-1871Y-284747D01*
X-561Y-283580D01*
X1185Y-283289D01*
X2713Y-283580D01*
X4024Y-284747D01*
X4679Y-286788D01*
Y-294955D01*
G01X18467Y-283289D02*
Y-294955D01*
G01Y-278622D02*
X18030Y-278330D01*
Y-277747D01*
X18467Y-277455D01*
X18904Y-277747D01*
Y-278330D01*
X18467Y-278622D01*
G01X32255Y-294955D02*
Y-283289D01*
G01Y-286205D02*
X33129Y-284747D01*
X34439Y-283580D01*
X36185Y-283289D01*
X37713Y-283580D01*
X39024Y-284747D01*
X39679Y-286788D01*
Y-294955D01*
G01X50410Y-299330D02*
X51939Y-300497D01*
X53685Y-300788D01*
X55213Y-300497D01*
X56524Y-299039D01*
X57397Y-296997D01*
Y-283289D01*
G01Y-285622D02*
X56524Y-284455D01*
X55213Y-283580D01*
X53685Y-283289D01*
X51939Y-283872D01*
X50847Y-285038D01*
X49973Y-287080D01*
X49537Y-289122D01*
X49755Y-290872D01*
X50629Y-292914D01*
X51939Y-294372D01*
X53685Y-294955D01*
X54995Y-294663D01*
X56524Y-293497D01*
X57397Y-292331D01*
G01X84100Y-294955D02*
Y-277455D01*
X89340D01*
X91087Y-278330D01*
X92397Y-280372D01*
X92834Y-282705D01*
X92397Y-285038D01*
X91305Y-286788D01*
X89340Y-287664D01*
X84100D01*
G01X101164Y-294955D02*
Y-277455D01*
X105530D01*
X107277Y-278330D01*
X108587Y-279497D01*
X109679Y-281246D01*
X110552Y-283289D01*
X110770Y-286205D01*
X110552Y-289122D01*
X109679Y-291164D01*
X108587Y-292914D01*
X107277Y-294080D01*
X105530Y-294955D01*
X101164D01*
G01X119100D02*
Y-277455D01*
X124340D01*
X126087Y-278330D01*
X127397Y-280372D01*
X127834Y-282705D01*
X127397Y-285038D01*
X126305Y-286788D01*
X124340Y-287664D01*
X119100D01*
G01X142713Y-285622D02*
X143587Y-284747D01*
X144242Y-283289D01*
X144679Y-281246D01*
X144242Y-279497D01*
X143369Y-278330D01*
X141840Y-277455D01*
X135945D01*
Y-294955D01*
X143150D01*
X144679Y-293789D01*
X145552Y-292038D01*
X145989Y-289997D01*
X145552Y-287955D01*
X144242Y-286205D01*
X142713Y-285622D01*
X135945D01*
G01X171600Y-294955D02*
Y-277455D01*
X176840D01*
X178587Y-278330D01*
X179897Y-280372D01*
X180334Y-282705D01*
X179897Y-285038D01*
X178805Y-286788D01*
X176840Y-287664D01*
X171600D01*
G01X188008Y-277455D02*
X193467Y-294955D01*
X198926Y-277455D01*
G01X210967D02*
Y-294955D01*
G01X205945Y-277455D02*
X215989D01*
G01X21540Y-249955D02*
Y-232455D01*
X27217Y-247038D01*
X32894Y-232455D01*
Y-249955D01*
G01X44717D02*
X43407Y-249663D01*
X42097Y-248497D01*
X41223Y-246455D01*
X40787Y-244122D01*
X41223Y-241788D01*
X42097Y-239747D01*
X43407Y-238580D01*
X44717Y-238289D01*
X46027Y-238580D01*
X47337Y-239747D01*
X48210Y-241788D01*
X48429Y-244122D01*
X48210Y-246455D01*
X47337Y-248497D01*
X46027Y-249663D01*
X44717Y-249955D01*
G01X66147Y-232455D02*
Y-249955D01*
G01Y-247331D02*
X65274Y-248789D01*
X63963Y-249663D01*
X62435Y-249955D01*
X60689Y-249372D01*
X59379Y-247914D01*
X58505Y-246164D01*
X58287Y-244122D01*
X58505Y-242080D01*
X59379Y-240330D01*
X60689Y-238872D01*
X62435Y-238289D01*
X63963Y-238580D01*
X65055Y-239164D01*
X66147Y-240330D01*
G01X76442Y-242080D02*
X83429D01*
X82774Y-240038D01*
X81682Y-238872D01*
X80154Y-238289D01*
X78625Y-238580D01*
X77315Y-239455D01*
X76442Y-241497D01*
X76005Y-243247D01*
Y-244997D01*
X76442Y-246747D01*
X77534Y-248497D01*
X78844Y-249663D01*
X80372Y-249955D01*
X81900Y-249372D01*
X83429Y-247622D01*
G01X97217Y-249955D02*
Y-232455D01*
G01X252500Y-249955D02*
Y-232455D01*
X257740D01*
X259487Y-233330D01*
X260797Y-235372D01*
X261234Y-237705D01*
X260797Y-240038D01*
X259705Y-241788D01*
X257740Y-242664D01*
X252500D01*
G01X279170Y-233914D02*
X277860Y-233038D01*
X276332Y-232455D01*
X274585D01*
X272620Y-233330D01*
X271092Y-234788D01*
X270000Y-236539D01*
X269127Y-239455D01*
X268908Y-242080D01*
X269345Y-244705D01*
X270000Y-246455D01*
X271310Y-248205D01*
X272839Y-249372D01*
X274367Y-249955D01*
X275895D01*
X277424Y-249372D01*
X278734Y-248497D01*
X279826Y-247331D01*
G01X293613Y-240622D02*
X294487Y-239747D01*
X295142Y-238289D01*
X295579Y-236246D01*
X295142Y-234497D01*
X294269Y-233330D01*
X292740Y-232455D01*
X286845D01*
Y-249955D01*
X294050D01*
X295579Y-248789D01*
X296452Y-247038D01*
X296889Y-244997D01*
X296452Y-242955D01*
X295142Y-241205D01*
X293613Y-240622D01*
X286845D01*
G01X302817Y-255788D02*
X315917D01*
G01X321845Y-249955D02*
Y-232455D01*
X331889Y-249955D01*
Y-232455D01*
G01X344367Y-249955D02*
X342620Y-249663D01*
X341092Y-248497D01*
X339782Y-246747D01*
X338908Y-244705D01*
X338472Y-242372D01*
Y-240038D01*
X338908Y-237705D01*
X339782Y-235663D01*
X341092Y-233914D01*
X342620Y-232747D01*
X344367Y-232455D01*
X346113Y-232747D01*
X347642Y-233914D01*
X348952Y-235663D01*
X349826Y-237705D01*
X350262Y-240038D01*
Y-242372D01*
X349826Y-244705D01*
X348952Y-246747D01*
X347642Y-248497D01*
X346113Y-249663D01*
X344367Y-249955D01*
G01X265617Y-294955D02*
Y-277455D01*
X262997Y-280955D01*
G01Y-294955D02*
X268237D01*
G01X278314Y-292331D02*
X279623Y-293789D01*
X281152Y-294663D01*
X283117Y-294955D01*
X285082Y-294372D01*
X286610Y-293205D01*
X287702Y-291164D01*
X287920Y-288830D01*
X287484Y-286497D01*
X286392Y-285038D01*
X284863Y-283872D01*
X283335Y-283580D01*
X281807Y-283872D01*
X279842Y-285038D01*
X280497Y-277455D01*
X286392D01*
G01X296469Y-287664D02*
X297997Y-285622D01*
X299307Y-284455D01*
X301054Y-283872D01*
X302582Y-284455D01*
X303674Y-285622D01*
X304547Y-287372D01*
X304765Y-289413D01*
X304547Y-291164D01*
X303674Y-292914D01*
X302363Y-294372D01*
X300835Y-294955D01*
X299089Y-294372D01*
X297560Y-292622D01*
X296687Y-289997D01*
X296469Y-287080D01*
X296905Y-283289D01*
X297560Y-281246D01*
X298652Y-279205D01*
X300180Y-277747D01*
X301709Y-277455D01*
X303237Y-278038D01*
X304329Y-279497D01*
G01X313969Y-287664D02*
X315497Y-285622D01*
X316807Y-284455D01*
X318554Y-283872D01*
X320082Y-284455D01*
X321174Y-285622D01*
X322047Y-287372D01*
X322265Y-289413D01*
X322047Y-291164D01*
X321174Y-292914D01*
X319863Y-294372D01*
X318335Y-294955D01*
X316589Y-294372D01*
X315060Y-292622D01*
X314187Y-289997D01*
X313969Y-287080D01*
X314405Y-283289D01*
X315060Y-281246D01*
X316152Y-279205D01*
X317680Y-277747D01*
X319209Y-277455D01*
X320737Y-278038D01*
X321829Y-279497D01*
G01X331905Y-292914D02*
X333434Y-294372D01*
X335180Y-294955D01*
X336927Y-294372D01*
X338455Y-292622D01*
X339547Y-289997D01*
X339984Y-287372D01*
Y-284164D01*
X339547Y-281539D01*
X338455Y-279205D01*
X337145Y-278038D01*
X335617Y-277455D01*
X333870Y-278038D01*
X332560Y-279205D01*
X331687Y-280955D01*
X331250Y-283289D01*
X331687Y-285330D01*
X332779Y-287372D01*
X334089Y-288539D01*
X335617Y-288830D01*
X337363Y-288247D01*
X338674Y-286788D01*
X339984Y-284164D01*
G01X395208Y-232455D02*
X400667Y-249955D01*
X406126Y-232455D01*
G01X422534Y-249955D02*
X413800D01*
Y-232455D01*
X422534D01*
G01X419040Y-240913D02*
X413800D01*
G01X431300Y-249955D02*
Y-232455D01*
X436759D01*
X438505Y-233330D01*
X439597Y-234497D01*
X440034Y-236830D01*
X439597Y-239164D01*
X438287Y-240622D01*
X436759Y-241497D01*
X431300D01*
G01X436759D02*
X440034Y-249955D01*
G01X453167Y-250538D02*
X452730Y-250247D01*
Y-249663D01*
X453167Y-249372D01*
X453604Y-249663D01*
Y-250247D01*
X453167Y-250538D01*
G01X426917Y-294955D02*
Y-277455D01*
X424297Y-280955D01*
G01Y-294955D02*
X429537D01*
G01X528750Y-232455D02*
Y-249955D01*
X537484D01*
G01X554547D02*
Y-238289D01*
G01Y-240330D02*
X553674Y-239164D01*
X552363Y-238580D01*
X550835Y-238289D01*
X549307Y-238872D01*
X547997Y-240038D01*
X547123Y-241788D01*
X546687Y-244122D01*
X547123Y-246455D01*
X547997Y-248205D01*
X549307Y-249372D01*
X550835Y-249955D01*
X552363Y-249663D01*
X553674Y-248789D01*
X554547Y-247622D01*
G01X563532Y-255205D02*
X564842Y-255788D01*
X566589Y-255205D01*
X567680Y-254039D01*
X568554Y-252580D01*
X569863Y-247914D01*
X572702Y-238289D01*
G01X565715D02*
X569863Y-247914D01*
G01X582342Y-242080D02*
X589329D01*
X588674Y-240038D01*
X587582Y-238872D01*
X586054Y-238289D01*
X584525Y-238580D01*
X583215Y-239455D01*
X582342Y-241497D01*
X581905Y-243247D01*
Y-244997D01*
X582342Y-246747D01*
X583434Y-248497D01*
X584744Y-249663D01*
X586272Y-249955D01*
X587800Y-249372D01*
X589329Y-247622D01*
G01X600060Y-249955D02*
Y-238289D01*
G01Y-240622D02*
X601152Y-239455D01*
X602244Y-238580D01*
X603772Y-238289D01*
X604863Y-238580D01*
X606174Y-239455D01*
G01X601371Y-285622D02*
X600497Y-284747D01*
X599842Y-283289D01*
X599405Y-281246D01*
X599842Y-279497D01*
X600715Y-278330D01*
X602244Y-277455D01*
X608139D01*
Y-294955D01*
X600934D01*
X599405Y-293789D01*
X598532Y-292038D01*
X598095Y-289997D01*
X598532Y-287955D01*
X599842Y-286205D01*
X601371Y-285622D01*
X608139D01*
G01X591294Y-294955D02*
Y-277455D01*
X585617Y-292038D01*
X579940Y-277455D01*
Y-294955D01*
G01X573576D02*
X568117Y-277455D01*
X562658Y-294955D01*
G01X564624Y-288830D02*
X571611D01*
G01X555202Y-292622D02*
X553455Y-294080D01*
X551490Y-294955D01*
X549744D01*
X547997Y-294080D01*
X546687Y-292622D01*
X546032Y-290580D01*
X546469Y-288539D01*
X547560Y-286788D01*
X549525Y-285622D01*
X552145Y-285038D01*
X553674Y-283872D01*
X554329Y-281830D01*
X553892Y-279788D01*
X552800Y-278330D01*
X551272Y-277455D01*
X549744D01*
X548215Y-278038D01*
X546905Y-279497D01*
G01X537920Y-294955D02*
Y-277455D01*
G01X529624D02*
X537920Y-288247D01*
G01X528314Y-294955D02*
X534209Y-283289D01*
G01X670864Y-249955D02*
Y-232455D01*
X675230D01*
X676977Y-233330D01*
X678287Y-234497D01*
X679379Y-236246D01*
X680252Y-238289D01*
X680470Y-241205D01*
X680252Y-244122D01*
X679379Y-246164D01*
X678287Y-247914D01*
X676977Y-249080D01*
X675230Y-249955D01*
X670864D01*
G01X689892Y-242080D02*
X696879D01*
X696224Y-240038D01*
X695132Y-238872D01*
X693604Y-238289D01*
X692075Y-238580D01*
X690765Y-239455D01*
X689892Y-241497D01*
X689455Y-243247D01*
Y-244997D01*
X689892Y-246747D01*
X690984Y-248497D01*
X692294Y-249663D01*
X693822Y-249955D01*
X695350Y-249372D01*
X696879Y-247622D01*
G01X707392Y-247914D02*
X708484Y-249080D01*
X710012Y-249955D01*
X711322D01*
X712632Y-249372D01*
X713505Y-248497D01*
X713942Y-247331D01*
X713724Y-245580D01*
X712850Y-244705D01*
X708920Y-242955D01*
X708047Y-240913D01*
X708484Y-239455D01*
X709357Y-238580D01*
X710667Y-238289D01*
X711977Y-238580D01*
X713287Y-239455D01*
G01X728167Y-238289D02*
Y-249955D01*
G01Y-233622D02*
X727730Y-233330D01*
Y-232747D01*
X728167Y-232455D01*
X728604Y-232747D01*
Y-233330D01*
X728167Y-233622D01*
G01X742610Y-254330D02*
X744139Y-255497D01*
X745885Y-255788D01*
X747413Y-255497D01*
X748724Y-254039D01*
X749597Y-251997D01*
Y-238289D01*
G01Y-240622D02*
X748724Y-239455D01*
X747413Y-238580D01*
X745885Y-238289D01*
X744139Y-238872D01*
X743047Y-240038D01*
X742173Y-242080D01*
X741737Y-244122D01*
X741955Y-245872D01*
X742829Y-247914D01*
X744139Y-249372D01*
X745885Y-249955D01*
X747195Y-249663D01*
X748724Y-248497D01*
X749597Y-247331D01*
G01X759455Y-249955D02*
Y-238289D01*
G01Y-241205D02*
X760329Y-239747D01*
X761639Y-238580D01*
X763385Y-238289D01*
X764913Y-238580D01*
X766224Y-239747D01*
X766879Y-241788D01*
Y-249955D01*
G01X777392Y-242080D02*
X784379D01*
X783724Y-240038D01*
X782632Y-238872D01*
X781104Y-238289D01*
X779575Y-238580D01*
X778265Y-239455D01*
X777392Y-241497D01*
X776955Y-243247D01*
Y-244997D01*
X777392Y-246747D01*
X778484Y-248497D01*
X779794Y-249663D01*
X781322Y-249955D01*
X782850Y-249372D01*
X784379Y-247622D01*
G01X795110Y-249955D02*
Y-238289D01*
G01Y-240622D02*
X796202Y-239455D01*
X797294Y-238580D01*
X798822Y-238289D01*
X799913Y-238580D01*
X801224Y-239455D01*
G01X660367Y-277455D02*
X663423Y-294955D01*
X666917Y-277455D01*
X670410Y-294955D01*
X673467Y-277455D01*
G01X680050Y-294955D02*
Y-277455D01*
X685290D01*
X687037Y-278330D01*
X688347Y-280372D01*
X688784Y-282705D01*
X688347Y-285038D01*
X687255Y-286788D01*
X685290Y-287664D01*
X680050D01*
G01X697332Y-294955D02*
Y-277455D01*
G01X706502D02*
Y-294955D01*
G01Y-286205D02*
X697332D01*
G01X716579Y-289122D02*
X722255D01*
G01X732769Y-294955D02*
Y-277455D01*
X741065D01*
G01X738009Y-285913D02*
X732769D01*
G01X750050Y-277455D02*
Y-294955D01*
X758784D01*
G01X771917D02*
X770170Y-294663D01*
X768642Y-293497D01*
X767332Y-291747D01*
X766458Y-289705D01*
X766022Y-287372D01*
Y-285038D01*
X766458Y-282705D01*
X767332Y-280663D01*
X768642Y-278914D01*
X770170Y-277747D01*
X771917Y-277455D01*
X773663Y-277747D01*
X775192Y-278914D01*
X776502Y-280663D01*
X777376Y-282705D01*
X777812Y-285038D01*
Y-287372D01*
X777376Y-289705D01*
X776502Y-291747D01*
X775192Y-293497D01*
X773663Y-294663D01*
X771917Y-294955D01*
G01X785050D02*
Y-277455D01*
X790509D01*
X792255Y-278330D01*
X793347Y-279497D01*
X793784Y-281830D01*
X793347Y-284164D01*
X792037Y-285622D01*
X790509Y-286497D01*
X785050D01*
G01X790509D02*
X793784Y-294955D01*
G01X801458D02*
X806917Y-277455D01*
X812376Y-294955D01*
G01X810410Y-288830D02*
X803423D01*
G01X841867Y-294955D02*
Y-277455D01*
X839247Y-280955D01*
G01Y-294955D02*
X844487D01*
G01X859367D02*
Y-277455D01*
X856747Y-280955D01*
G01Y-294955D02*
X861987D01*
G01X872937Y-295538D02*
X880797Y-277455D01*
G01X894367Y-294955D02*
Y-277455D01*
X891747Y-280955D01*
G01Y-294955D02*
X896987D01*
G01X907719Y-287664D02*
X909247Y-285622D01*
X910557Y-284455D01*
X912304Y-283872D01*
X913832Y-284455D01*
X914924Y-285622D01*
X915797Y-287372D01*
X916015Y-289413D01*
X915797Y-291164D01*
X914924Y-292914D01*
X913613Y-294372D01*
X912085Y-294955D01*
X910339Y-294372D01*
X908810Y-292622D01*
X907937Y-289997D01*
X907719Y-287080D01*
X908155Y-283289D01*
X908810Y-281246D01*
X909902Y-279205D01*
X911430Y-277747D01*
X912959Y-277455D01*
X914487Y-278038D01*
X915579Y-279497D01*
G01X925437Y-295538D02*
X933297Y-277455D01*
G01X942719Y-280372D02*
X944029Y-278622D01*
X945557Y-277747D01*
X947304Y-277455D01*
X949487Y-278038D01*
X951015Y-279497D01*
X951452Y-281246D01*
X951234Y-282997D01*
X950360Y-284455D01*
X945994Y-287372D01*
X944029Y-289413D01*
X942719Y-292331D01*
X942282Y-294955D01*
X951452D01*
G01X964367Y-277455D02*
X962620Y-278038D01*
X961310Y-279497D01*
X960437Y-281246D01*
X959782Y-283580D01*
X959564Y-286205D01*
X959782Y-288830D01*
X960437Y-291164D01*
X961310Y-292914D01*
X962620Y-294372D01*
X964367Y-294955D01*
X966113Y-294372D01*
X967424Y-292914D01*
X968297Y-291164D01*
X968952Y-288830D01*
X969170Y-286205D01*
X968952Y-283580D01*
X968297Y-281246D01*
X967424Y-279497D01*
X966113Y-278038D01*
X964367Y-277455D01*
G01X981867Y-294955D02*
Y-277455D01*
X979247Y-280955D01*
G01Y-294955D02*
X984487D01*
G01X995219Y-287664D02*
X996747Y-285622D01*
X998057Y-284455D01*
X999804Y-283872D01*
X1001332Y-284455D01*
X1002424Y-285622D01*
X1003297Y-287372D01*
X1003515Y-289413D01*
X1003297Y-291164D01*
X1002424Y-292914D01*
X1001113Y-294372D01*
X999585Y-294955D01*
X997839Y-294372D01*
X996310Y-292622D01*
X995437Y-289997D01*
X995219Y-287080D01*
X995655Y-283289D01*
X996310Y-281246D01*
X997402Y-279205D01*
X998930Y-277747D01*
X1000459Y-277455D01*
X1001987Y-278038D01*
X1003079Y-279497D01*
G01X889564Y-249955D02*
Y-232455D01*
X893930D01*
X895677Y-233330D01*
X896987Y-234497D01*
X898079Y-236246D01*
X898952Y-238289D01*
X899170Y-241205D01*
X898952Y-244122D01*
X898079Y-246164D01*
X896987Y-247914D01*
X895677Y-249080D01*
X893930Y-249955D01*
X889564D01*
G01X915797D02*
Y-238289D01*
G01Y-240330D02*
X914924Y-239164D01*
X913613Y-238580D01*
X912085Y-238289D01*
X910557Y-238872D01*
X909247Y-240038D01*
X908373Y-241788D01*
X907937Y-244122D01*
X908373Y-246455D01*
X909247Y-248205D01*
X910557Y-249372D01*
X912085Y-249955D01*
X913613Y-249663D01*
X914924Y-248789D01*
X915797Y-247622D01*
G01X929367Y-232455D02*
Y-249955D01*
G01X926310Y-238289D02*
X932424D01*
G01X943592Y-242080D02*
X950579D01*
X949924Y-240038D01*
X948832Y-238872D01*
X947304Y-238289D01*
X945775Y-238580D01*
X944465Y-239455D01*
X943592Y-241497D01*
X943155Y-243247D01*
Y-244997D01*
X943592Y-246747D01*
X944684Y-248497D01*
X945994Y-249663D01*
X947522Y-249955D01*
X949050Y-249372D01*
X950579Y-247622D01*
G54D14*
X11811Y571426D03*
Y949378D03*
Y1067489D03*
Y1484811D03*
Y1445441D03*
Y1862763D03*
G54D15*
X8858Y629693D03*
Y626544D03*
Y623394D03*
Y620245D03*
Y617095D03*
Y613945D03*
Y610796D03*
Y607646D03*
Y604496D03*
Y601347D03*
Y598197D03*
Y702134D03*
Y698985D03*
Y695835D03*
Y692685D03*
Y689536D03*
Y686386D03*
Y683237D03*
Y680087D03*
Y676937D03*
Y673788D03*
Y670638D03*
Y667489D03*
Y664339D03*
Y661189D03*
Y658040D03*
Y654890D03*
Y651741D03*
Y648591D03*
Y645441D03*
Y642292D03*
Y639142D03*
Y635993D03*
Y632843D03*
Y774575D03*
Y771426D03*
Y768276D03*
Y765126D03*
Y761977D03*
Y758827D03*
Y755678D03*
Y752528D03*
Y749378D03*
Y733630D03*
Y730481D03*
Y727331D03*
Y724182D03*
Y721032D03*
Y717882D03*
Y714733D03*
Y711583D03*
Y708433D03*
Y705284D03*
Y847016D03*
Y843867D03*
Y840717D03*
Y837567D03*
Y834418D03*
Y831268D03*
Y828119D03*
Y824969D03*
Y821819D03*
Y818670D03*
Y815520D03*
Y812371D03*
Y809221D03*
Y806071D03*
Y802922D03*
Y799772D03*
Y796622D03*
Y793473D03*
Y790323D03*
Y787174D03*
Y784024D03*
Y780874D03*
Y777725D03*
Y919457D03*
Y916308D03*
Y913158D03*
Y910008D03*
Y906859D03*
Y903709D03*
Y900559D03*
Y897410D03*
Y894260D03*
Y891111D03*
Y887961D03*
Y884811D03*
Y881662D03*
Y878512D03*
Y875363D03*
Y872213D03*
Y869063D03*
Y865914D03*
Y862764D03*
Y859615D03*
Y856465D03*
Y853315D03*
Y850166D03*
Y922607D03*
Y1138355D03*
Y1135205D03*
Y1132056D03*
Y1128906D03*
Y1125756D03*
Y1122607D03*
Y1119457D03*
Y1116308D03*
Y1113158D03*
Y1110008D03*
Y1106859D03*
Y1103709D03*
Y1100559D03*
Y1097410D03*
Y1094260D03*
Y1210796D03*
Y1207646D03*
Y1204496D03*
Y1201347D03*
Y1198197D03*
Y1195048D03*
Y1191898D03*
Y1188748D03*
Y1185599D03*
Y1182449D03*
Y1179300D03*
Y1176150D03*
Y1173000D03*
Y1169851D03*
Y1166701D03*
Y1163552D03*
Y1160402D03*
Y1157252D03*
Y1154103D03*
Y1150953D03*
Y1147804D03*
Y1144654D03*
Y1141504D03*
Y1283237D03*
Y1280087D03*
Y1276937D03*
Y1273788D03*
Y1270638D03*
Y1267489D03*
Y1264339D03*
Y1261189D03*
Y1258040D03*
Y1254890D03*
Y1251741D03*
Y1248591D03*
Y1245441D03*
Y1229693D03*
Y1226544D03*
Y1223394D03*
Y1220245D03*
Y1217095D03*
Y1213945D03*
Y1355678D03*
Y1352528D03*
Y1349378D03*
Y1346229D03*
Y1343079D03*
Y1339930D03*
Y1336780D03*
Y1333630D03*
Y1330481D03*
Y1327331D03*
Y1324182D03*
Y1321032D03*
Y1317882D03*
Y1314733D03*
Y1311583D03*
Y1308434D03*
Y1305284D03*
Y1302134D03*
Y1298985D03*
Y1295835D03*
Y1292685D03*
Y1289536D03*
Y1286386D03*
Y1418670D03*
Y1415520D03*
Y1412371D03*
Y1409221D03*
Y1406071D03*
Y1402922D03*
Y1399772D03*
Y1396622D03*
Y1393473D03*
Y1390323D03*
Y1387174D03*
Y1384024D03*
Y1380874D03*
Y1377725D03*
Y1374575D03*
Y1371426D03*
Y1368276D03*
Y1365126D03*
Y1361977D03*
Y1358827D03*
Y1574574D03*
Y1571425D03*
Y1568275D03*
Y1565126D03*
Y1561976D03*
Y1558826D03*
Y1555677D03*
Y1552527D03*
Y1549378D03*
Y1546228D03*
Y1543078D03*
Y1539929D03*
Y1536779D03*
Y1533630D03*
Y1530480D03*
Y1527330D03*
Y1524181D03*
Y1521031D03*
Y1517881D03*
Y1514732D03*
Y1511582D03*
Y1647015D03*
Y1643866D03*
Y1640716D03*
Y1637567D03*
Y1634417D03*
Y1631267D03*
Y1628118D03*
Y1624968D03*
Y1621818D03*
Y1618669D03*
Y1615519D03*
Y1612370D03*
Y1609220D03*
Y1606070D03*
Y1602921D03*
Y1599771D03*
Y1596622D03*
Y1593472D03*
Y1590322D03*
Y1587173D03*
Y1584023D03*
Y1580874D03*
Y1577724D03*
Y1719456D03*
Y1716307D03*
Y1713157D03*
Y1710007D03*
Y1706858D03*
Y1703708D03*
Y1700559D03*
Y1697409D03*
Y1694259D03*
Y1691110D03*
Y1687960D03*
Y1684811D03*
Y1681661D03*
Y1678511D03*
Y1675362D03*
Y1672212D03*
Y1669063D03*
Y1665913D03*
Y1662763D03*
Y1791897D03*
Y1788748D03*
Y1785598D03*
Y1782448D03*
Y1779299D03*
Y1776149D03*
Y1773000D03*
Y1769850D03*
Y1766700D03*
Y1763551D03*
Y1760401D03*
Y1757252D03*
Y1754102D03*
Y1750952D03*
Y1747803D03*
Y1744653D03*
Y1741504D03*
Y1738354D03*
Y1735204D03*
Y1732055D03*
Y1728905D03*
Y1725756D03*
Y1722606D03*
Y1835992D03*
Y1832842D03*
Y1829693D03*
Y1826543D03*
Y1823393D03*
Y1820244D03*
Y1817094D03*
Y1813944D03*
Y1810795D03*
Y1807645D03*
Y1804496D03*
Y1801346D03*
Y1798196D03*
Y1795047D03*
G54D16*
X37000Y762000D03*
X25000Y988000D03*
X27825Y995000D03*
X105750Y217750D03*
X73900Y269500D03*
X78675Y380704D03*
X47500Y660500D03*
X80100Y805500D03*
X80215Y787900D03*
X43387Y803500D03*
X40087Y788400D03*
X41000Y908000D03*
X56000Y967000D03*
X45000Y1057000D03*
X81175Y1066404D03*
X51944Y1232506D03*
X79390Y1327082D03*
X65000Y1336000D03*
X50100Y1317400D03*
X94642Y1456100D03*
X77607Y1565391D03*
X55738Y1578587D03*
X58777Y1585826D03*
X49555Y1583740D03*
X45402Y1712309D03*
X45150Y1720650D03*
X55500Y1763000D03*
X83600Y1736600D03*
X53200Y1865800D03*
X63579Y1894881D03*
X70650Y1897792D03*
X50100Y1872800D03*
X183344Y808200D03*
X126221Y861250D03*
Y853750D03*
X148000Y966500D03*
X142066Y958234D03*
X141250Y978050D03*
X132000Y1042000D03*
X112700Y1079600D03*
X163170Y1210999D03*
X162500Y1380500D03*
X117387Y1536250D03*
Y1543750D03*
X122844Y1672400D03*
X130344D03*
X122000Y1727500D03*
X147200Y1756600D03*
X157900Y1770500D03*
X213244Y23725D03*
X243156Y382060D03*
X235656D03*
X228156Y438500D03*
X220656D03*
X206700Y575000D03*
X190844Y808200D03*
X242700Y1266656D03*
Y1259156D03*
X243590Y1779507D03*
X232344Y1740000D03*
X239844D03*
X320700Y396100D03*
X318700Y469800D03*
X328250Y441400D03*
X284000Y541344D03*
Y548844D03*
X318800Y823700D03*
X317156Y1193440D03*
X324656D03*
X276344Y1183060D03*
X268844D03*
X328250Y1233000D03*
X311500Y1374500D03*
X401500Y395500D03*
X393500Y422000D03*
X401500Y830000D03*
X390000Y820500D03*
X393500Y852000D03*
X402000Y1196500D03*
X396637Y1176000D03*
X383140Y1179640D03*
X358156Y1411000D03*
X350656D03*
X402000Y1695000D03*
X379500Y1673750D03*
X335025Y1701725D03*
X395500Y1703000D03*
X427500Y297156D03*
Y304656D03*
X412500Y1130750D03*
Y1138250D03*
X438656Y1669000D03*
X431156D03*
X458156Y1743000D03*
X450656D03*
X512656Y623500D03*
X520156D03*
X555000Y524344D03*
Y531844D03*
X689000Y1592500D03*
X719901Y939198D03*
X740464Y1499388D03*
X698500Y1812000D03*
X807756Y377775D03*
X808256Y783275D03*
X807756Y1188775D03*
X831000Y1625000D03*
X807756Y1594275D03*
X851000Y1627000D03*
X903500Y1627500D03*
X873500Y1625500D03*
X975000Y1425000D03*
X950000Y1440000D03*
X960000Y1460000D03*
X950000Y1470000D03*
Y1500000D03*
X960000Y1540000D03*
X950000Y1550000D03*
X940000Y1570000D03*
Y1605000D03*
X933500Y1625000D03*
X961500Y1624500D03*
X931000Y1671500D03*
X979500Y1669750D03*
Y1662250D03*
X930000Y1685000D03*
X939500Y1698000D03*
X913000Y1717750D03*
G54D17*
X33469Y1029523D03*
X269690Y1490152D03*
G54D18*
G01X-106883Y-224955D02*
Y-304955D01*
G01Y-260455D02*
X1019417D01*
G01X-106883Y-304955D02*
X1019417D01*
G01X-110883Y-208955D02*
G02I-12000J0D01*
G01X-116033D02*
G02I-6850J0D01*
G01X-122883Y-224955D02*
Y-192955D01*
G01X-106883Y-208955D02*
X-138883D01*
G01X-106883Y-224955D02*
X1019417D01*
G01X231917D02*
Y-304955D01*
G01X369417Y-224955D02*
Y-304955D01*
G01X484417Y-224955D02*
Y-304955D01*
G01X651917Y-224955D02*
Y-304955D01*
G01X821917Y-224955D02*
Y-304955D01*
G01X1019417Y-224955D02*
Y-304955D01*
G01X1047417Y-208955D02*
G02I-12000J0D01*
G01X1042267D02*
G02I-6850J0D01*
G01X1035417Y-224955D02*
Y-192955D01*
G01X1051417Y-208955D02*
X1019417D01*
X38800Y1810100D03*
X22100Y1802800D03*
X38317Y1804491D03*
X34900Y1807200D03*
X35100Y1813000D03*
X26500Y1805200D03*
X26600Y1810600D03*
X26300Y1815000D03*
X30800Y1805300D03*
Y1810500D03*
X17500Y1801900D03*
X22000Y1814100D03*
Y1809100D03*
X17500Y1806900D03*
Y1811900D03*
Y1816500D03*
X7600Y1855000D03*
X17500Y1827500D03*
X22600Y1825200D03*
X17500Y1832500D03*
X22500Y1830000D03*
X17500Y1837500D03*
X22500Y1835000D03*
X17500Y1842500D03*
X22500Y1840000D03*
X17500Y1847500D03*
X22500Y1845000D03*
X17500Y1852500D03*
X22500Y1850000D03*
X17500Y1857500D03*
X22500Y1855000D03*
Y1865000D03*
X17500Y1867500D03*
X22500Y1860000D03*
X12500Y1845000D03*
Y1850000D03*
Y1855000D03*
Y1840000D03*
X17500Y1872500D03*
X22500Y1870000D03*
X12500D03*
X71200Y36900D03*
X136100Y41200D03*
X935000Y1425000D03*
X984900Y1430400D03*
X953800Y1424900D03*
X945000Y1425000D03*
X935000Y1455000D03*
Y1475000D03*
Y1445000D03*
Y1465000D03*
Y1435000D03*
X945000Y1475000D03*
X955000D03*
X965000D03*
X945000Y1465000D03*
X955000D03*
X965000D03*
X945000Y1455000D03*
X955000D03*
X965000D03*
X945000Y1445000D03*
X955000D03*
X965000D03*
X945000Y1435000D03*
X955000D03*
X965000D03*
Y1495000D03*
X955000D03*
X935000Y1485000D03*
Y1495000D03*
X945000D03*
Y1485000D03*
X955000D03*
X965000D03*
X975000Y1495000D03*
Y1485000D03*
Y1475000D03*
Y1465000D03*
Y1455000D03*
Y1445000D03*
Y1435000D03*
X965000Y1525000D03*
X955000D03*
X945000D03*
Y1516000D03*
X955000D03*
X965000D03*
X935000Y1555000D03*
X945000D03*
X955000D03*
X965000D03*
X935000Y1575000D03*
Y1565000D03*
X945000Y1575000D03*
X955000D03*
X965000D03*
Y1565000D03*
X955000D03*
X945000D03*
X935000Y1545000D03*
Y1535000D03*
Y1525000D03*
Y1516000D03*
X965000Y1545000D03*
X955000D03*
X945000D03*
Y1535000D03*
X955000D03*
X965000D03*
X975000Y1565000D03*
Y1575000D03*
Y1525000D03*
Y1535000D03*
Y1545000D03*
Y1555000D03*
X935000Y1505000D03*
X955000D03*
X945000D03*
X965000D03*
Y1605000D03*
X935000Y1595000D03*
Y1585000D03*
X945000Y1595000D03*
X955000D03*
X965000D03*
Y1585000D03*
X955000D03*
X945000D03*
X975000Y1595000D03*
Y1605000D03*
Y1585000D03*
X990600Y1427100D03*
X995000Y1425000D03*
X1005000D03*
G54D19*
X72835Y17047D03*
Y190275D03*
Y422559D03*
Y595787D03*
Y828071D03*
Y1001299D03*
Y1233583D03*
Y1406811D03*
Y1639095D03*
Y1812323D03*
X171260Y179803D03*
Y353031D03*
Y585315D03*
Y758543D03*
Y990827D03*
Y1164055D03*
Y1396339D03*
Y1569567D03*
Y1801851D03*
Y1975079D03*
X899606Y179803D03*
Y353031D03*
Y585315D03*
Y758543D03*
Y990827D03*
Y1164055D03*
Y1396339D03*
Y1569567D03*
Y1801851D03*
Y1975079D03*
M02*
